(kicad_pcb
	(version 20260206)
	(generator "pcbnew")
	(generator_version "10.0")
	(general
		(thickness 1.6)
		(legacy_teardrops no)
	)
	(paper "A4")
	(title_block
		(title "03242023_DA0F0TMBIJ0_F0T_Motherboard_J_brd_V01_OCP.brd")
		(comment 1 "Grand Teton / footprints 4141-4146 of 6105")
	)
	(layers
		(0 "F.Cu" signal "TOP")
		(4 "In1.Cu" signal "GND")
		(6 "In2.Cu" signal "IN1")
		(8 "In3.Cu" signal "GND1")
		(10 "In4.Cu" signal "IN2")
		(12 "In5.Cu" signal "GND2")
		(14 "In6.Cu" signal "IN3")
		(16 "In7.Cu" signal "GND3")
		(18 "In8.Cu" signal "VCC")
		(20 "In9.Cu" signal "VCC1")
		(22 "In10.Cu" signal "GND4")
		(24 "In11.Cu" signal "IN4")
		(26 "In12.Cu" signal "GND5")
		(28 "In13.Cu" signal "IN5")
		(30 "In14.Cu" signal "GND6")
		(32 "In15.Cu" signal "IN6")
		(34 "In16.Cu" signal "GND7")
		(2 "B.Cu" signal "BOTTOM")
		(9 "F.Adhes" user "F.Adhesive")
		(11 "B.Adhes" user "B.Adhesive")
		(13 "F.Paste" user "Package Geometry/Pastemask Top")
		(15 "B.Paste" user "Package Geometry/Pastemask Bottom")
		(5 "F.SilkS" user "Ref Des/Silkscreen Top")
		(7 "B.SilkS" user "Ref Des/Silkscreen Bottom")
		(1 "F.Mask" user "Board Geometry/Soldermask Top")
		(3 "B.Mask" user "Board Geometry/Soldermask Bottom")
		(17 "Dwgs.User" user "User.Drawings")
		(19 "Cmts.User" user "User.Comments")
		(21 "Eco1.User" user "User.Eco1")
		(23 "Eco2.User" user "User.Eco2")
		(25 "Edge.Cuts" user "Board Geometry/Outline")
		(27 "Margin" user)
		(31 "F.CrtYd" user "Package Geometry/Place Bound Top")
		(29 "B.CrtYd" user "Package Geometry/Place Bound Bottom")
		(35 "F.Fab" user "Ref Des/Assembly Top")
		(33 "B.Fab" user "Ref Des/Assembly Bottom")
	)
	(footprint ""
		(layer "F.Cu")
		(at 366.06988 -296.05478 180)
		(property "Reference" "C219"
			(at 0 0 180)
			(layer "F.SilkS")
			(hide yes)
			(effects
				(font
					(size 1.27 1.27)
				)
			)
		)
		(property "Value" ""
			(at 0 0 180)
			(layer "F.Fab")
			(effects
				(font
					(size 1.27 1.27)
				)
			)
		)
		(duplicate_pad_numbers_are_jumpers no)
		(fp_line
			(start 1.524 0.762)
			(end -1.524 0.762)
			(stroke
				(width 0.1524)
				(type default)
			)
			(layer "F.SilkS")
		)
		(fp_line
			(start 1.524 -0.762)
			(end 1.524 0.762)
			(stroke
				(width 0.1524)
				(type default)
			)
			(layer "F.SilkS")
		)
		(fp_line
			(start -1.524 0.762)
			(end -1.524 -0.762)
			(stroke
				(width 0.1524)
				(type default)
			)
			(layer "F.SilkS")
		)
		(fp_line
			(start -1.524 -0.762)
			(end 1.524 -0.762)
			(stroke
				(width 0.1524)
				(type default)
			)
			(layer "F.SilkS")
		)
		(fp_line
			(start 1.1049 0.724916)
			(end 1.1049 -0.724916)
			(stroke
				(width 0.1)
				(type default)
			)
			(layer "F.Fab")
		)
		(fp_line
			(start 1.1049 -0.724916)
			(end -1.1049 -0.724916)
			(stroke
				(width 0.1)
				(type default)
			)
			(layer "F.Fab")
		)
		(fp_line
			(start -1.1049 0.724916)
			(end 1.1049 0.724916)
			(stroke
				(width 0.1)
				(type default)
			)
			(layer "F.Fab")
		)
		(fp_line
			(start -1.1049 -0.724916)
			(end -1.1049 0.724916)
			(stroke
				(width 0.1)
				(type default)
			)
			(layer "F.Fab")
		)
		(pad "1" smd rect
			(at -0.889 0)
			(size 1.016 1.27)
			(layers "F.Cu" "F.Mask" "F.Paste")
			(net "PVCCIN_CPU0")
		)
		(pad "2" smd rect
			(at 0.889 0)
			(size 1.016 1.27)
			(layers "F.Cu" "F.Mask" "F.Paste")
			(net "GND")
		)
	)
	(footprint ""
		(layer "F.Cu")
		(at 239.152684 -57.41289 180)
		(property "Reference" "C1990"
			(at 0 0 180)
			(layer "F.SilkS")
			(hide yes)
			(effects
				(font
					(size 1.27 1.27)
				)
			)
		)
		(property "Value" ""
			(at 0 0 180)
			(layer "F.Fab")
			(effects
				(font
					(size 1.27 1.27)
				)
			)
		)
		(duplicate_pad_numbers_are_jumpers no)
		(fp_line
			(start 0.299974 0.150114)
			(end -0.299974 0.150114)
			(stroke
				(width 0.1)
				(type default)
			)
			(layer "F.Fab")
		)
		(fp_line
			(start 0.299974 -0.150114)
			(end 0.299974 0.150114)
			(stroke
				(width 0.1)
				(type default)
			)
			(layer "F.Fab")
		)
		(fp_line
			(start -0.299974 0.150114)
			(end -0.299974 -0.150114)
			(stroke
				(width 0.1)
				(type default)
			)
			(layer "F.Fab")
		)
		(fp_line
			(start -0.299974 -0.150114)
			(end 0.299974 -0.150114)
			(stroke
				(width 0.1)
				(type default)
			)
			(layer "F.Fab")
		)
		(pad "1" smd rect
			(at -0.2667 0 180)
			(size 0.3048 0.381)
			(layers "F.Cu" "F.Mask" "F.Paste")
			(net "P3E_PCH_E1S_TX_DN<3>")
		)
		(pad "2" smd rect
			(at 0.2667 0 180)
			(size 0.3048 0.381)
			(layers "F.Cu" "F.Mask" "F.Paste")
			(net "P3E_PCH_E1S_TX_C_DN<3>")
		)
		(zone
			(layer "In1.Cu")
			(hatch none 0.5)
			(connect_pads
				(clearance 0)
			)
			(min_thickness 0.25)
			(keepout
				(tracks not_allowed)
				(vias allowed)
				(pads allowed)
				(copperpour not_allowed)
				(footprints allowed)
			)
			(placement
				(enabled no)
				(sheetname "")
			)
			(fill
				(thermal_gap 0.5)
				(thermal_bridge_width 0.5)
				(island_removal_mode 0)
			)
			(polygon
				(pts
					(arc
						(start 239.012984 -57.653174)
						(mid 239.066866 -57.630856)
						(end 239.089184 -57.576974)
					)
					(arc
						(start 239.089184 -57.246774)
						(mid 239.066866 -57.192892)
						(end 239.012984 -57.170574)
					)
					(arc
						(start 238.758984 -57.170574)
						(mid 238.705102 -57.192892)
						(end 238.682784 -57.246774)
					)
					(arc
						(start 238.682784 -57.576974)
						(mid 238.705102 -57.630856)
						(end 238.758984 -57.653174)
					)
				)
			)
		)
		(zone
			(layer "In1.Cu")
			(hatch none 0.5)
			(connect_pads
				(clearance 0)
			)
			(min_thickness 0.25)
			(keepout
				(tracks not_allowed)
				(vias allowed)
				(pads allowed)
				(copperpour not_allowed)
				(footprints allowed)
			)
			(placement
				(enabled no)
				(sheetname "")
			)
			(fill
				(thermal_gap 0.5)
				(thermal_bridge_width 0.5)
				(island_removal_mode 0)
			)
			(polygon
				(pts
					(arc
						(start 239.546384 -57.653174)
						(mid 239.600266 -57.630856)
						(end 239.622584 -57.576974)
					)
					(arc
						(start 239.622584 -57.246774)
						(mid 239.600266 -57.192892)
						(end 239.546384 -57.170574)
					)
					(arc
						(start 239.292384 -57.170574)
						(mid 239.238502 -57.192892)
						(end 239.216184 -57.246774)
					)
					(arc
						(start 239.216184 -57.576974)
						(mid 239.238502 -57.630856)
						(end 239.292384 -57.653174)
					)
				)
			)
		)
	)
	(footprint ""
		(layer "F.Cu")
		(at 450.307202 -77.829918 90)
		(property "Reference" "PR833"
			(at 0 0 90)
			(layer "F.SilkS")
			(hide yes)
			(effects
				(font
					(size 1.27 1.27)
				)
			)
		)
		(property "Value" ""
			(at 0 0 90)
			(layer "F.Fab")
			(effects
				(font
					(size 1.27 1.27)
				)
			)
		)
		(duplicate_pad_numbers_are_jumpers no)
		(fp_line
			(start 0.7874 -0.4064)
			(end 0.7874 0.4064)
			(stroke
				(width 0.1524)
				(type default)
			)
			(layer "F.SilkS")
		)
		(fp_line
			(start -0.7874 -0.4064)
			(end 0.7874 -0.4064)
			(stroke
				(width 0.1524)
				(type default)
			)
			(layer "F.SilkS")
		)
		(fp_line
			(start 0.7874 0.4064)
			(end -0.7874 0.4064)
			(stroke
				(width 0.1524)
				(type default)
			)
			(layer "F.SilkS")
		)
		(fp_line
			(start -0.7874 0.4064)
			(end -0.7874 -0.4064)
			(stroke
				(width 0.1524)
				(type default)
			)
			(layer "F.SilkS")
		)
		(fp_line
			(start -0.12065 -0.305054)
			(end -0.12065 -0.2794)
			(stroke
				(width 0.1)
				(type default)
			)
			(layer "F.Fab")
		)
		(fp_line
			(start -0.67945 -0.305054)
			(end -0.12065 -0.305054)
			(stroke
				(width 0.1)
				(type default)
			)
			(layer "F.Fab")
		)
		(fp_line
			(start 0.67945 -0.3048)
			(end 0.67945 0.3048)
			(stroke
				(width 0.1)
				(type default)
			)
			(layer "F.Fab")
		)
		(fp_line
			(start 0.12065 -0.3048)
			(end 0.67945 -0.3048)
			(stroke
				(width 0.1)
				(type default)
			)
			(layer "F.Fab")
		)
		(fp_line
			(start 0.12065 -0.2794)
			(end 0.12065 -0.3048)
			(stroke
				(width 0.1)
				(type default)
			)
			(layer "F.Fab")
		)
		(fp_line
			(start -0.12065 -0.2794)
			(end 0.12065 -0.2794)
			(stroke
				(width 0.1)
				(type default)
			)
			(layer "F.Fab")
		)
		(fp_line
			(start 0.120396 0.2794)
			(end -0.12065 0.2794)
			(stroke
				(width 0.1)
				(type default)
			)
			(layer "F.Fab")
		)
		(fp_line
			(start -0.12065 0.2794)
			(end -0.12065 0.3048)
			(stroke
				(width 0.1)
				(type default)
			)
			(layer "F.Fab")
		)
		(fp_line
			(start 0.67945 0.3048)
			(end 0.120396 0.3048)
			(stroke
				(width 0.1)
				(type default)
			)
			(layer "F.Fab")
		)
		(fp_line
			(start 0.120396 0.3048)
			(end 0.120396 0.2794)
			(stroke
				(width 0.1)
				(type default)
			)
			(layer "F.Fab")
		)
		(fp_line
			(start -0.12065 0.3048)
			(end -0.67945 0.3048)
			(stroke
				(width 0.1)
				(type default)
			)
			(layer "F.Fab")
		)
		(fp_line
			(start -0.67945 0.3048)
			(end -0.67945 -0.305054)
			(stroke
				(width 0.1)
				(type default)
			)
			(layer "F.Fab")
		)
		(pad "1" smd circle
			(at -0.40005 0 90)
			(size 0 0)
			(layers "F.Cu" "F.Mask" "F.Paste")
			(net "P3V3_AUX_SS")
		)
		(pad "2" smd circle
			(at 0.40005 0 90)
			(size 0 0)
			(layers "F.Cu" "F.Mask" "F.Paste")
			(net "GND")
		)
	)
	(footprint ""
		(layer "F.Cu")
		(at 284.589728 -413.23768 -90)
		(property "Reference" "R4551"
			(at 0 0 270)
			(layer "F.SilkS")
			(hide yes)
			(effects
				(font
					(size 1.27 1.27)
				)
			)
		)
		(property "Value" ""
			(at 0 0 270)
			(layer "F.Fab")
			(effects
				(font
					(size 1.27 1.27)
				)
			)
		)
		(duplicate_pad_numbers_are_jumpers no)
		(fp_line
			(start -0.7874 0.4064)
			(end -0.7874 -0.4064)
			(stroke
				(width 0.1524)
				(type default)
			)
			(layer "F.SilkS")
		)
		(fp_line
			(start 0.7874 0.4064)
			(end -0.7874 0.4064)
			(stroke
				(width 0.1524)
				(type default)
			)
			(layer "F.SilkS")
		)
		(fp_line
			(start -0.7874 -0.4064)
			(end 0.7874 -0.4064)
			(stroke
				(width 0.1524)
				(type default)
			)
			(layer "F.SilkS")
		)
		(fp_line
			(start 0.7874 -0.4064)
			(end 0.7874 0.4064)
			(stroke
				(width 0.1524)
				(type default)
			)
			(layer "F.SilkS")
		)
		(fp_line
			(start -0.67945 0.3048)
			(end -0.67945 -0.305054)
			(stroke
				(width 0.1)
				(type default)
			)
			(layer "F.Fab")
		)
		(fp_line
			(start -0.12065 0.3048)
			(end -0.67945 0.3048)
			(stroke
				(width 0.1)
				(type default)
			)
			(layer "F.Fab")
		)
		(fp_line
			(start 0.120396 0.3048)
			(end 0.120396 0.2794)
			(stroke
				(width 0.1)
				(type default)
			)
			(layer "F.Fab")
		)
		(fp_line
			(start 0.67945 0.3048)
			(end 0.120396 0.3048)
			(stroke
				(width 0.1)
				(type default)
			)
			(layer "F.Fab")
		)
		(fp_line
			(start -0.12065 0.2794)
			(end -0.12065 0.3048)
			(stroke
				(width 0.1)
				(type default)
			)
			(layer "F.Fab")
		)
		(fp_line
			(start 0.120396 0.2794)
			(end -0.12065 0.2794)
			(stroke
				(width 0.1)
				(type default)
			)
			(layer "F.Fab")
		)
		(fp_line
			(start -0.12065 -0.2794)
			(end 0.12065 -0.2794)
			(stroke
				(width 0.1)
				(type default)
			)
			(layer "F.Fab")
		)
		(fp_line
			(start 0.12065 -0.2794)
			(end 0.12065 -0.3048)
			(stroke
				(width 0.1)
				(type default)
			)
			(layer "F.Fab")
		)
		(fp_line
			(start 0.12065 -0.3048)
			(end 0.67945 -0.3048)
			(stroke
				(width 0.1)
				(type default)
			)
			(layer "F.Fab")
		)
		(fp_line
			(start 0.67945 -0.3048)
			(end 0.67945 0.3048)
			(stroke
				(width 0.1)
				(type default)
			)
			(layer "F.Fab")
		)
		(fp_line
			(start -0.67945 -0.305054)
			(end -0.12065 -0.305054)
			(stroke
				(width 0.1)
				(type default)
			)
			(layer "F.Fab")
		)
		(fp_line
			(start -0.12065 -0.305054)
			(end -0.12065 -0.2794)
			(stroke
				(width 0.1)
				(type default)
			)
			(layer "F.Fab")
		)
		(pad "1" smd circle
			(at -0.40005 0 270)
			(size 0 0)
			(layers "F.Cu" "F.Mask" "F.Paste")
			(net "P3V3_AUX")
		)
		(pad "2" smd circle
			(at 0.40005 0 270)
			(size 0 0)
			(layers "F.Cu" "F.Mask" "F.Paste")
			(net "HPDB_HSC_PWRGD")
		)
	)
	(footprint ""
		(layer "F.Cu")
		(at 162.573462 -22.36089)
		(property "Reference" "R4151"
			(at 0 0 0)
			(layer "F.SilkS")
			(hide yes)
			(effects
				(font
					(size 1.27 1.27)
				)
			)
		)
		(property "Value" ""
			(at 0 0 0)
			(layer "F.Fab")
			(effects
				(font
					(size 1.27 1.27)
				)
			)
		)
		(duplicate_pad_numbers_are_jumpers no)
		(fp_line
			(start -0.7874 -0.4064)
			(end 0.7874 -0.4064)
			(stroke
				(width 0.1524)
				(type default)
			)
			(layer "F.SilkS")
		)
		(fp_line
			(start -0.7874 0.4064)
			(end -0.7874 -0.4064)
			(stroke
				(width 0.1524)
				(type default)
			)
			(layer "F.SilkS")
		)
		(fp_line
			(start 0.7874 -0.4064)
			(end 0.7874 0.4064)
			(stroke
				(width 0.1524)
				(type default)
			)
			(layer "F.SilkS")
		)
		(fp_line
			(start 0.7874 0.4064)
			(end -0.7874 0.4064)
			(stroke
				(width 0.1524)
				(type default)
			)
			(layer "F.SilkS")
		)
		(fp_line
			(start -0.67945 -0.305054)
			(end -0.12065 -0.305054)
			(stroke
				(width 0.1)
				(type default)
			)
			(layer "F.Fab")
		)
		(fp_line
			(start -0.67945 0.3048)
			(end -0.67945 -0.305054)
			(stroke
				(width 0.1)
				(type default)
			)
			(layer "F.Fab")
		)
		(fp_line
			(start -0.12065 -0.305054)
			(end -0.12065 -0.2794)
			(stroke
				(width 0.1)
				(type default)
			)
			(layer "F.Fab")
		)
		(fp_line
			(start -0.12065 -0.2794)
			(end 0.12065 -0.2794)
			(stroke
				(width 0.1)
				(type default)
			)
			(layer "F.Fab")
		)
		(fp_line
			(start -0.12065 0.2794)
			(end -0.12065 0.3048)
			(stroke
				(width 0.1)
				(type default)
			)
			(layer "F.Fab")
		)
		(fp_line
			(start -0.12065 0.3048)
			(end -0.67945 0.3048)
			(stroke
				(width 0.1)
				(type default)
			)
			(layer "F.Fab")
		)
		(fp_line
			(start 0.120396 0.2794)
			(end -0.12065 0.2794)
			(stroke
				(width 0.1)
				(type default)
			)
			(layer "F.Fab")
		)
		(fp_line
			(start 0.120396 0.3048)
			(end 0.120396 0.2794)
			(stroke
				(width 0.1)
				(type default)
			)
			(layer "F.Fab")
		)
		(fp_line
			(start 0.12065 -0.3048)
			(end 0.67945 -0.3048)
			(stroke
				(width 0.1)
				(type default)
			)
			(layer "F.Fab")
		)
		(fp_line
			(start 0.12065 -0.2794)
			(end 0.12065 -0.3048)
			(stroke
				(width 0.1)
				(type default)
			)
			(layer "F.Fab")
		)
		(fp_line
			(start 0.67945 -0.3048)
			(end 0.67945 0.3048)
			(stroke
				(width 0.1)
				(type default)
			)
			(layer "F.Fab")
		)
		(fp_line
			(start 0.67945 0.3048)
			(end 0.120396 0.3048)
			(stroke
				(width 0.1)
				(type default)
			)
			(layer "F.Fab")
		)
		(pad "1" smd circle
			(at -0.40005 0)
			(size 0 0)
			(layers "F.Cu" "F.Mask" "F.Paste")
			(net "SMB_1_PLD_3V3AUX_SCL")
		)
		(pad "2" smd circle
			(at 0.40005 0)
			(size 0 0)
			(layers "F.Cu" "F.Mask" "F.Paste")
			(net "SMB_2_PLD_3V3AUX_SCL_R1")
		)
	)
	(footprint ""
		(layer "F.Cu")
		(at 86.311994 -31.667958 90)
		(property "Reference" "R4602"
			(at 0 0 90)
			(layer "F.SilkS")
			(hide yes)
			(effects
				(font
					(size 1.27 1.27)
				)
			)
		)
		(property "Value" ""
			(at 0 0 90)
			(layer "F.Fab")
			(effects
				(font
					(size 1.27 1.27)
				)
			)
		)
		(duplicate_pad_numbers_are_jumpers no)
		(fp_line
			(start 0.7874 -0.4064)
			(end 0.7874 0.4064)
			(stroke
				(width 0.1524)
				(type default)
			)
			(layer "F.SilkS")
		)
		(fp_line
			(start -0.7874 -0.4064)
			(end 0.7874 -0.4064)
			(stroke
				(width 0.1524)
				(type default)
			)
			(layer "F.SilkS")
		)
		(fp_line
			(start 0.7874 0.4064)
			(end -0.7874 0.4064)
			(stroke
				(width 0.1524)
				(type default)
			)
			(layer "F.SilkS")
		)
		(fp_line
			(start -0.7874 0.4064)
			(end -0.7874 -0.4064)
			(stroke
				(width 0.1524)
				(type default)
			)
			(layer "F.SilkS")
		)
		(fp_line
			(start -0.12065 -0.305054)
			(end -0.12065 -0.2794)
			(stroke
				(width 0.1)
				(type default)
			)
			(layer "F.Fab")
		)
		(fp_line
			(start -0.67945 -0.305054)
			(end -0.12065 -0.305054)
			(stroke
				(width 0.1)
				(type default)
			)
			(layer "F.Fab")
		)
		(fp_line
			(start 0.67945 -0.3048)
			(end 0.67945 0.3048)
			(stroke
				(width 0.1)
				(type default)
			)
			(layer "F.Fab")
		)
		(fp_line
			(start 0.12065 -0.3048)
			(end 0.67945 -0.3048)
			(stroke
				(width 0.1)
				(type default)
			)
			(layer "F.Fab")
		)
		(fp_line
			(start 0.12065 -0.2794)
			(end 0.12065 -0.3048)
			(stroke
				(width 0.1)
				(type default)
			)
			(layer "F.Fab")
		)
		(fp_line
			(start -0.12065 -0.2794)
			(end 0.12065 -0.2794)
			(stroke
				(width 0.1)
				(type default)
			)
			(layer "F.Fab")
		)
		(fp_line
			(start 0.120396 0.2794)
			(end -0.12065 0.2794)
			(stroke
				(width 0.1)
				(type default)
			)
			(layer "F.Fab")
		)
		(fp_line
			(start -0.12065 0.2794)
			(end -0.12065 0.3048)
			(stroke
				(width 0.1)
				(type default)
			)
			(layer "F.Fab")
		)
		(fp_line
			(start 0.67945 0.3048)
			(end 0.120396 0.3048)
			(stroke
				(width 0.1)
				(type default)
			)
			(layer "F.Fab")
		)
		(fp_line
			(start 0.120396 0.3048)
			(end 0.120396 0.2794)
			(stroke
				(width 0.1)
				(type default)
			)
			(layer "F.Fab")
		)
		(fp_line
			(start -0.12065 0.3048)
			(end -0.67945 0.3048)
			(stroke
				(width 0.1)
				(type default)
			)
			(layer "F.Fab")
		)
		(fp_line
			(start -0.67945 0.3048)
			(end -0.67945 -0.305054)
			(stroke
				(width 0.1)
				(type default)
			)
			(layer "F.Fab")
		)
		(pad "1" smd circle
			(at -0.40005 0 90)
			(size 0 0)
			(layers "F.Cu" "F.Mask" "F.Paste")
			(net "CLK_50M_NCSI_OCP_V3_2_ISO")
		)
		(pad "2" smd circle
			(at 0.40005 0 90)
			(size 0 0)
			(layers "F.Cu" "F.Mask" "F.Paste")
			(net "CLK_50M_NCSI_OCP_V3_2_ISO_R")
		)
	)
)
